(kicad_pcb
	(version 20260206)
	(generator "pcbnew")
	(generator_version "10.0")
	(general
		(thickness 1.6)
		(legacy_teardrops no)
	)
	(paper "A4")
	(title_block
		(title "12092022_DA0F0TFB6D0_F0T_FAN_BOARD_MP5048_D_brd_v02_OCP.brd")
		(comment 1 "Grand Teton / footprints 572-577 of 924")
	)
	(layers
		(0 "F.Cu" signal "TOP")
		(4 "In1.Cu" signal "GND")
		(6 "In2.Cu" signal "IN1")
		(8 "In3.Cu" signal "IN2")
		(10 "In4.Cu" signal "GND1")
		(2 "B.Cu" signal "BOTTOM")
		(9 "F.Adhes" user "F.Adhesive")
		(11 "B.Adhes" user "B.Adhesive")
		(13 "F.Paste" user "Package Geometry/Pastemask Top")
		(15 "B.Paste" user "Package Geometry/Pastemask Bottom")
		(5 "F.SilkS" user "Ref Des/Silkscreen Top")
		(7 "B.SilkS" user "Ref Des/Silkscreen Bottom")
		(1 "F.Mask" user "Board Geometry/Soldermask Top")
		(3 "B.Mask" user "Board Geometry/Soldermask Bottom")
		(17 "Dwgs.User" user "User.Drawings")
		(19 "Cmts.User" user "User.Comments")
		(21 "Eco1.User" user "User.Eco1")
		(23 "Eco2.User" user "User.Eco2")
		(25 "Edge.Cuts" user "Board Geometry/Outline")
		(27 "Margin" user)
		(31 "F.CrtYd" user "Package Geometry/Place Bound Top")
		(29 "B.CrtYd" user "Package Geometry/Place Bound Bottom")
		(35 "F.Fab" user "Ref Des/Assembly Top")
		(33 "B.Fab" user "Ref Des/Assembly Bottom")
	)
	(footprint ""
		(layer "F.Cu")
		(at 43.561 -175.895)
		(property "Reference" "R5100"
			(at 0 0 0)
			(layer "F.SilkS")
			(hide yes)
			(effects
				(font
					(size 1.27 1.27)
				)
			)
		)
		(property "Value" ""
			(at 0 0 0)
			(layer "F.Fab")
			(effects
				(font
					(size 1.27 1.27)
				)
			)
		)
		(duplicate_pad_numbers_are_jumpers no)
		(fp_line
			(start -0.7874 -0.4064)
			(end 0.7874 -0.4064)
			(stroke
				(width 0.1524)
				(type default)
			)
			(layer "F.SilkS")
		)
		(fp_line
			(start -0.7874 0.4064)
			(end -0.7874 -0.4064)
			(stroke
				(width 0.1524)
				(type default)
			)
			(layer "F.SilkS")
		)
		(fp_line
			(start 0.7874 -0.4064)
			(end 0.7874 0.4064)
			(stroke
				(width 0.1524)
				(type default)
			)
			(layer "F.SilkS")
		)
		(fp_line
			(start 0.7874 0.4064)
			(end -0.7874 0.4064)
			(stroke
				(width 0.1524)
				(type default)
			)
			(layer "F.SilkS")
		)
		(fp_line
			(start -0.67945 -0.305054)
			(end -0.12065 -0.305054)
			(stroke
				(width 0.1)
				(type default)
			)
			(layer "F.Fab")
		)
		(fp_line
			(start -0.67945 0.3048)
			(end -0.67945 -0.305054)
			(stroke
				(width 0.1)
				(type default)
			)
			(layer "F.Fab")
		)
		(fp_line
			(start -0.12065 -0.305054)
			(end -0.12065 -0.2794)
			(stroke
				(width 0.1)
				(type default)
			)
			(layer "F.Fab")
		)
		(fp_line
			(start -0.12065 -0.2794)
			(end 0.12065 -0.2794)
			(stroke
				(width 0.1)
				(type default)
			)
			(layer "F.Fab")
		)
		(fp_line
			(start -0.12065 0.2794)
			(end -0.12065 0.3048)
			(stroke
				(width 0.1)
				(type default)
			)
			(layer "F.Fab")
		)
		(fp_line
			(start -0.12065 0.3048)
			(end -0.67945 0.3048)
			(stroke
				(width 0.1)
				(type default)
			)
			(layer "F.Fab")
		)
		(fp_line
			(start 0.120396 0.2794)
			(end -0.12065 0.2794)
			(stroke
				(width 0.1)
				(type default)
			)
			(layer "F.Fab")
		)
		(fp_line
			(start 0.120396 0.3048)
			(end 0.120396 0.2794)
			(stroke
				(width 0.1)
				(type default)
			)
			(layer "F.Fab")
		)
		(fp_line
			(start 0.12065 -0.3048)
			(end 0.67945 -0.3048)
			(stroke
				(width 0.1)
				(type default)
			)
			(layer "F.Fab")
		)
		(fp_line
			(start 0.12065 -0.2794)
			(end 0.12065 -0.3048)
			(stroke
				(width 0.1)
				(type default)
			)
			(layer "F.Fab")
		)
		(fp_line
			(start 0.67945 -0.3048)
			(end 0.67945 0.3048)
			(stroke
				(width 0.1)
				(type default)
			)
			(layer "F.Fab")
		)
		(fp_line
			(start 0.67945 0.3048)
			(end 0.120396 0.3048)
			(stroke
				(width 0.1)
				(type default)
			)
			(layer "F.Fab")
		)
		(pad "1" smd circle
			(at -0.40005 0)
			(size 0 0)
			(layers "F.Cu" "F.Mask" "F.Paste")
			(net "FAN_3_OK_LED")
		)
		(pad "2" smd circle
			(at 0.40005 0)
			(size 0 0)
			(layers "F.Cu" "F.Mask" "F.Paste")
			(net "FAN_3_OK_R_LED")
		)
	)
	(footprint ""
		(layer "F.Cu")
		(at 14.0589 -131.064 180)
		(property "Reference" "R5592"
			(at 0 0 180)
			(layer "F.SilkS")
			(hide yes)
			(effects
				(font
					(size 1.27 1.27)
				)
			)
		)
		(property "Value" ""
			(at 0 0 180)
			(layer "F.Fab")
			(effects
				(font
					(size 1.27 1.27)
				)
			)
		)
		(duplicate_pad_numbers_are_jumpers no)
		(fp_line
			(start 0.7874 0.4064)
			(end -0.7874 0.4064)
			(stroke
				(width 0.1524)
				(type default)
			)
			(layer "F.SilkS")
		)
		(fp_line
			(start 0.7874 -0.4064)
			(end 0.7874 0.4064)
			(stroke
				(width 0.1524)
				(type default)
			)
			(layer "F.SilkS")
		)
		(fp_line
			(start -0.7874 0.4064)
			(end -0.7874 -0.4064)
			(stroke
				(width 0.1524)
				(type default)
			)
			(layer "F.SilkS")
		)
		(fp_line
			(start -0.7874 -0.4064)
			(end 0.7874 -0.4064)
			(stroke
				(width 0.1524)
				(type default)
			)
			(layer "F.SilkS")
		)
		(fp_line
			(start 0.67945 0.3048)
			(end 0.120396 0.3048)
			(stroke
				(width 0.1)
				(type default)
			)
			(layer "F.Fab")
		)
		(fp_line
			(start 0.67945 -0.3048)
			(end 0.67945 0.3048)
			(stroke
				(width 0.1)
				(type default)
			)
			(layer "F.Fab")
		)
		(fp_line
			(start 0.12065 -0.2794)
			(end 0.12065 -0.3048)
			(stroke
				(width 0.1)
				(type default)
			)
			(layer "F.Fab")
		)
		(fp_line
			(start 0.12065 -0.3048)
			(end 0.67945 -0.3048)
			(stroke
				(width 0.1)
				(type default)
			)
			(layer "F.Fab")
		)
		(fp_line
			(start 0.120396 0.3048)
			(end 0.120396 0.2794)
			(stroke
				(width 0.1)
				(type default)
			)
			(layer "F.Fab")
		)
		(fp_line
			(start 0.120396 0.2794)
			(end -0.12065 0.2794)
			(stroke
				(width 0.1)
				(type default)
			)
			(layer "F.Fab")
		)
		(fp_line
			(start -0.12065 0.3048)
			(end -0.67945 0.3048)
			(stroke
				(width 0.1)
				(type default)
			)
			(layer "F.Fab")
		)
		(fp_line
			(start -0.12065 0.2794)
			(end -0.12065 0.3048)
			(stroke
				(width 0.1)
				(type default)
			)
			(layer "F.Fab")
		)
		(fp_line
			(start -0.12065 -0.2794)
			(end 0.12065 -0.2794)
			(stroke
				(width 0.1)
				(type default)
			)
			(layer "F.Fab")
		)
		(fp_line
			(start -0.12065 -0.305054)
			(end -0.12065 -0.2794)
			(stroke
				(width 0.1)
				(type default)
			)
			(layer "F.Fab")
		)
		(fp_line
			(start -0.67945 0.3048)
			(end -0.67945 -0.305054)
			(stroke
				(width 0.1)
				(type default)
			)
			(layer "F.Fab")
		)
		(fp_line
			(start -0.67945 -0.305054)
			(end -0.12065 -0.305054)
			(stroke
				(width 0.1)
				(type default)
			)
			(layer "F.Fab")
		)
		(pad "1" smd rect
			(at -0.40005 0)
			(size 0.4572 0.508)
			(layers "F.Cu" "F.Mask" "F.Paste")
			(net "FAN_6_TACH_IL")
		)
		(pad "2" smd rect
			(at 0.40005 0)
			(size 0.4572 0.508)
			(layers "F.Cu" "F.Mask" "F.Paste")
			(net "FAN_6_TACH_IL_R2")
		)
	)
	(footprint ""
		(layer "F.Cu")
		(at 8.709914 -66.986912 180)
		(property "Reference" "C2061"
			(at 0 0 180)
			(layer "F.SilkS")
			(hide yes)
			(effects
				(font
					(size 1.27 1.27)
				)
			)
		)
		(property "Value" ""
			(at 0 0 180)
			(layer "F.Fab")
			(effects
				(font
					(size 1.27 1.27)
				)
			)
		)
		(duplicate_pad_numbers_are_jumpers no)
		(fp_line
			(start 0.7874 0.4064)
			(end -0.7874 0.4064)
			(stroke
				(width 0.1524)
				(type default)
			)
			(layer "F.SilkS")
		)
		(fp_line
			(start 0.7874 -0.4064)
			(end 0.7874 0.4064)
			(stroke
				(width 0.1524)
				(type default)
			)
			(layer "F.SilkS")
		)
		(fp_line
			(start -0.7874 0.4064)
			(end -0.7874 -0.4064)
			(stroke
				(width 0.1524)
				(type default)
			)
			(layer "F.SilkS")
		)
		(fp_line
			(start -0.7874 -0.4064)
			(end 0.7874 -0.4064)
			(stroke
				(width 0.1524)
				(type default)
			)
			(layer "F.SilkS")
		)
		(fp_line
			(start 0.67945 0.3048)
			(end 0.120396 0.3048)
			(stroke
				(width 0.1)
				(type default)
			)
			(layer "F.Fab")
		)
		(fp_line
			(start 0.67945 -0.3048)
			(end 0.67945 0.3048)
			(stroke
				(width 0.1)
				(type default)
			)
			(layer "F.Fab")
		)
		(fp_line
			(start 0.12065 -0.2794)
			(end 0.12065 -0.3048)
			(stroke
				(width 0.1)
				(type default)
			)
			(layer "F.Fab")
		)
		(fp_line
			(start 0.12065 -0.3048)
			(end 0.67945 -0.3048)
			(stroke
				(width 0.1)
				(type default)
			)
			(layer "F.Fab")
		)
		(fp_line
			(start 0.120396 0.3048)
			(end 0.120396 0.2794)
			(stroke
				(width 0.1)
				(type default)
			)
			(layer "F.Fab")
		)
		(fp_line
			(start 0.120396 0.2794)
			(end -0.12065 0.2794)
			(stroke
				(width 0.1)
				(type default)
			)
			(layer "F.Fab")
		)
		(fp_line
			(start -0.12065 0.3048)
			(end -0.67945 0.3048)
			(stroke
				(width 0.1)
				(type default)
			)
			(layer "F.Fab")
		)
		(fp_line
			(start -0.12065 0.2794)
			(end -0.12065 0.3048)
			(stroke
				(width 0.1)
				(type default)
			)
			(layer "F.Fab")
		)
		(fp_line
			(start -0.12065 -0.2794)
			(end 0.12065 -0.2794)
			(stroke
				(width 0.1)
				(type default)
			)
			(layer "F.Fab")
		)
		(fp_line
			(start -0.12065 -0.305054)
			(end -0.12065 -0.2794)
			(stroke
				(width 0.1)
				(type default)
			)
			(layer "F.Fab")
		)
		(fp_line
			(start -0.67945 0.3048)
			(end -0.67945 -0.305054)
			(stroke
				(width 0.1)
				(type default)
			)
			(layer "F.Fab")
		)
		(fp_line
			(start -0.67945 -0.305054)
			(end -0.12065 -0.305054)
			(stroke
				(width 0.1)
				(type default)
			)
			(layer "F.Fab")
		)
		(pad "1" smd circle
			(at -0.40005 0 180)
			(size 0 0)
			(layers "F.Cu" "F.Mask" "F.Paste")
			(net "P3V3_AUX")
		)
		(pad "2" smd circle
			(at 0.40005 0 180)
			(size 0 0)
			(layers "F.Cu" "F.Mask" "F.Paste")
			(net "GND")
		)
	)
	(footprint ""
		(layer "F.Cu")
		(at 32.893 -27.362912)
		(property "Reference" "D286"
			(at -5.461 0.084582 0)
			(unlocked yes)
			(layer "F.SilkS")
			(effects
				(font
					(size 0.7874 0.5842)
					(thickness 0.1524)
				)
				(justify left)
			)
		)
		(property "Value" ""
			(at 0 0 0)
			(layer "F.Fab")
			(effects
				(font
					(size 1.27 1.27)
				)
			)
		)
		(duplicate_pad_numbers_are_jumpers no)
		(fp_line
			(start -0.854964 -0.450088)
			(end -0.854964 0.450088)
			(stroke
				(width 0.1524)
				(type default)
			)
			(layer "F.SilkS")
		)
		(fp_line
			(start -0.854964 0.450088)
			(end 0.925068 0.450088)
			(stroke
				(width 0.1524)
				(type default)
			)
			(layer "F.SilkS")
		)
		(fp_line
			(start 0.845058 0.4064)
			(end 0.845058 -0.381)
			(stroke
				(width 0.1524)
				(type default)
			)
			(layer "F.SilkS")
		)
		(fp_line
			(start 0.870458 -0.2794)
			(end 0.845058 0.4064)
			(stroke
				(width 0.1524)
				(type default)
			)
			(layer "F.SilkS")
		)
		(fp_line
			(start 0.94488 -0.450088)
			(end -0.854964 -0.450088)
			(stroke
				(width 0.1524)
				(type default)
			)
			(layer "F.SilkS")
		)
		(fp_line
			(start 0.94488 0.450088)
			(end 0.94488 -0.450088)
			(stroke
				(width 0.1524)
				(type default)
			)
			(layer "F.SilkS")
		)
		(fp_line
			(start -0.54991 -0.350012)
			(end -0.54991 0.350012)
			(stroke
				(width 0.1)
				(type default)
			)
			(layer "F.Fab")
		)
		(fp_line
			(start -0.54991 0.350012)
			(end 0.54991 0.350012)
			(stroke
				(width 0.1)
				(type default)
			)
			(layer "F.Fab")
		)
		(fp_line
			(start 0.54991 -0.350012)
			(end -0.54991 -0.350012)
			(stroke
				(width 0.1)
				(type default)
			)
			(layer "F.Fab")
		)
		(fp_line
			(start 0.54991 0.350012)
			(end 0.54991 -0.350012)
			(stroke
				(width 0.1)
				(type default)
			)
			(layer "F.Fab")
		)
		(fp_text user "+"
			(at 0.1016 1.346962 180)
			(unlocked yes)
			(layer "F.SilkS")
			(effects
				(font
					(size 1.905 1.4224)
					(thickness 0.1524)
				)
				(justify left)
			)
		)
		(fp_text user "-"
			(at 1.651 1.042162 180)
			(unlocked yes)
			(layer "F.SilkS")
			(effects
				(font
					(size 1.905 1.4224)
					(thickness 0.1524)
				)
				(justify left)
			)
		)
		(fp_text user "+"
			(at -0.808228 0.239014 180)
			(unlocked yes)
			(layer "F.Fab")
			(effects
				(font
					(size 1.905 1.4224)
					(thickness 0.1524)
				)
				(justify left)
			)
		)
		(fp_text user "-"
			(at 2.48539 0.239014 180)
			(unlocked yes)
			(layer "F.Fab")
			(effects
				(font
					(size 1.905 1.4224)
					(thickness 0.1524)
				)
				(justify left)
			)
		)
		(pad "A" smd rect
			(at -0.424942 0)
			(size 0.5588 0.6096)
			(layers "F.Cu" "F.Mask" "F.Paste")
			(net "GND")
		)
		(pad "C" smd rect
			(at 0.424942 0 180)
			(size 0.5588 0.6096)
			(layers "F.Cu" "F.Mask" "F.Paste")
			(net "FAN_3_PWM_IL_R")
		)
	)
	(footprint ""
		(layer "F.Cu")
		(at 18.034 -133.985 90)
		(property "Reference" "R4945"
			(at 0 0 90)
			(layer "F.SilkS")
			(hide yes)
			(effects
				(font
					(size 1.27 1.27)
				)
			)
		)
		(property "Value" ""
			(at 0 0 90)
			(layer "F.Fab")
			(effects
				(font
					(size 1.27 1.27)
				)
			)
		)
		(duplicate_pad_numbers_are_jumpers no)
		(fp_line
			(start 0.7874 -0.4064)
			(end 0.7874 0.4064)
			(stroke
				(width 0.1524)
				(type default)
			)
			(layer "F.SilkS")
		)
		(fp_line
			(start -0.7874 -0.4064)
			(end 0.7874 -0.4064)
			(stroke
				(width 0.1524)
				(type default)
			)
			(layer "F.SilkS")
		)
		(fp_line
			(start 0.7874 0.4064)
			(end -0.7874 0.4064)
			(stroke
				(width 0.1524)
				(type default)
			)
			(layer "F.SilkS")
		)
		(fp_line
			(start -0.7874 0.4064)
			(end -0.7874 -0.4064)
			(stroke
				(width 0.1524)
				(type default)
			)
			(layer "F.SilkS")
		)
		(fp_line
			(start -0.12065 -0.305054)
			(end -0.12065 -0.2794)
			(stroke
				(width 0.1)
				(type default)
			)
			(layer "F.Fab")
		)
		(fp_line
			(start -0.67945 -0.305054)
			(end -0.12065 -0.305054)
			(stroke
				(width 0.1)
				(type default)
			)
			(layer "F.Fab")
		)
		(fp_line
			(start 0.67945 -0.3048)
			(end 0.67945 0.3048)
			(stroke
				(width 0.1)
				(type default)
			)
			(layer "F.Fab")
		)
		(fp_line
			(start 0.12065 -0.3048)
			(end 0.67945 -0.3048)
			(stroke
				(width 0.1)
				(type default)
			)
			(layer "F.Fab")
		)
		(fp_line
			(start 0.12065 -0.2794)
			(end 0.12065 -0.3048)
			(stroke
				(width 0.1)
				(type default)
			)
			(layer "F.Fab")
		)
		(fp_line
			(start -0.12065 -0.2794)
			(end 0.12065 -0.2794)
			(stroke
				(width 0.1)
				(type default)
			)
			(layer "F.Fab")
		)
		(fp_line
			(start 0.120396 0.2794)
			(end -0.12065 0.2794)
			(stroke
				(width 0.1)
				(type default)
			)
			(layer "F.Fab")
		)
		(fp_line
			(start -0.12065 0.2794)
			(end -0.12065 0.3048)
			(stroke
				(width 0.1)
				(type default)
			)
			(layer "F.Fab")
		)
		(fp_line
			(start 0.67945 0.3048)
			(end 0.120396 0.3048)
			(stroke
				(width 0.1)
				(type default)
			)
			(layer "F.Fab")
		)
		(fp_line
			(start 0.120396 0.3048)
			(end 0.120396 0.2794)
			(stroke
				(width 0.1)
				(type default)
			)
			(layer "F.Fab")
		)
		(fp_line
			(start -0.12065 0.3048)
			(end -0.67945 0.3048)
			(stroke
				(width 0.1)
				(type default)
			)
			(layer "F.Fab")
		)
		(fp_line
			(start -0.67945 0.3048)
			(end -0.67945 -0.305054)
			(stroke
				(width 0.1)
				(type default)
			)
			(layer "F.Fab")
		)
		(pad "1" smd circle
			(at -0.40005 0 90)
			(size 0 0)
			(layers "F.Cu" "F.Mask" "F.Paste")
			(net "MAX31790_U330_WD_START")
		)
		(pad "2" smd circle
			(at 0.40005 0 90)
			(size 0 0)
			(layers "F.Cu" "F.Mask" "F.Paste")
			(net "P3V3_AUX")
		)
	)
	(footprint ""
		(layer "F.Cu")
		(at 29.21 -107.188 -90)
		(property "Reference" "R5520"
			(at 0 0 270)
			(layer "F.SilkS")
			(hide yes)
			(effects
				(font
					(size 1.27 1.27)
				)
			)
		)
		(property "Value" ""
			(at 0 0 270)
			(layer "F.Fab")
			(effects
				(font
					(size 1.27 1.27)
				)
			)
		)
		(duplicate_pad_numbers_are_jumpers no)
		(fp_line
			(start -0.7874 0.4064)
			(end -0.7874 -0.4064)
			(stroke
				(width 0.1524)
				(type default)
			)
			(layer "F.SilkS")
		)
		(fp_line
			(start 0.7874 0.4064)
			(end -0.7874 0.4064)
			(stroke
				(width 0.1524)
				(type default)
			)
			(layer "F.SilkS")
		)
		(fp_line
			(start -0.7874 -0.4064)
			(end 0.7874 -0.4064)
			(stroke
				(width 0.1524)
				(type default)
			)
			(layer "F.SilkS")
		)
		(fp_line
			(start 0.7874 -0.4064)
			(end 0.7874 0.4064)
			(stroke
				(width 0.1524)
				(type default)
			)
			(layer "F.SilkS")
		)
		(fp_line
			(start -0.67945 0.3048)
			(end -0.67945 -0.305054)
			(stroke
				(width 0.1)
				(type default)
			)
			(layer "F.Fab")
		)
		(fp_line
			(start -0.12065 0.3048)
			(end -0.67945 0.3048)
			(stroke
				(width 0.1)
				(type default)
			)
			(layer "F.Fab")
		)
		(fp_line
			(start 0.120396 0.3048)
			(end 0.120396 0.2794)
			(stroke
				(width 0.1)
				(type default)
			)
			(layer "F.Fab")
		)
		(fp_line
			(start 0.67945 0.3048)
			(end 0.120396 0.3048)
			(stroke
				(width 0.1)
				(type default)
			)
			(layer "F.Fab")
		)
		(fp_line
			(start -0.12065 0.2794)
			(end -0.12065 0.3048)
			(stroke
				(width 0.1)
				(type default)
			)
			(layer "F.Fab")
		)
		(fp_line
			(start 0.120396 0.2794)
			(end -0.12065 0.2794)
			(stroke
				(width 0.1)
				(type default)
			)
			(layer "F.Fab")
		)
		(fp_line
			(start -0.12065 -0.2794)
			(end 0.12065 -0.2794)
			(stroke
				(width 0.1)
				(type default)
			)
			(layer "F.Fab")
		)
		(fp_line
			(start 0.12065 -0.2794)
			(end 0.12065 -0.3048)
			(stroke
				(width 0.1)
				(type default)
			)
			(layer "F.Fab")
		)
		(fp_line
			(start 0.12065 -0.3048)
			(end 0.67945 -0.3048)
			(stroke
				(width 0.1)
				(type default)
			)
			(layer "F.Fab")
		)
		(fp_line
			(start 0.67945 -0.3048)
			(end 0.67945 0.3048)
			(stroke
				(width 0.1)
				(type default)
			)
			(layer "F.Fab")
		)
		(fp_line
			(start -0.67945 -0.305054)
			(end -0.12065 -0.305054)
			(stroke
				(width 0.1)
				(type default)
			)
			(layer "F.Fab")
		)
		(fp_line
			(start -0.12065 -0.305054)
			(end -0.12065 -0.2794)
			(stroke
				(width 0.1)
				(type default)
			)
			(layer "F.Fab")
		)
		(pad "1" smd circle
			(at -0.40005 0 270)
			(size 0 0)
			(layers "F.Cu" "F.Mask" "F.Paste")
			(net "P3V3_AUX")
		)
		(pad "2" smd circle
			(at 0.40005 0 270)
			(size 0 0)
			(layers "F.Cu" "F.Mask" "F.Paste")
			(net "FAN_5_PWM")
		)
	)
)
